(kicad_pcb
	(version 20260206)
	(generator "pcbnew")
	(generator_version "10.0")
	(general
		(thickness 1.6)
		(legacy_teardrops no)
	)
	(paper "A4")
	(title_block
		(title "peb — Lightning_PEB_BRD.brd")
		(comment 1 "Lightning (Wiwynn / Facebook NVMe JBOF) / footprints 785-792 of 2563")
	)
	(layers
		(0 "F.Cu" signal "TOP")
		(4 "In1.Cu" signal "L2GND")
		(6 "In2.Cu" signal "L3")
		(8 "In3.Cu" signal "L4VCC")
		(10 "In4.Cu" signal "L5VCC")
		(12 "In5.Cu" signal "L6")
		(14 "In6.Cu" signal "L7GND")
		(2 "B.Cu" signal "BOTTOM")
		(9 "F.Adhes" user "F.Adhesive")
		(11 "B.Adhes" user "B.Adhesive")
		(13 "F.Paste" user "Package Geometry/Pastemask Top")
		(15 "B.Paste" user "Package Geometry/Pastemask Bottom")
		(5 "F.SilkS" user "Ref Des/Silkscreen Top")
		(7 "B.SilkS" user "Ref Des/Silkscreen Bottom")
		(1 "F.Mask" user "Board Geometry/Soldermask Top")
		(3 "B.Mask" user "Board Geometry/Soldermask Bottom")
		(17 "Dwgs.User" user "User.Drawings")
		(19 "Cmts.User" user "User.Comments")
		(21 "Eco1.User" user "User.Eco1")
		(23 "Eco2.User" user "User.Eco2")
		(25 "Edge.Cuts" user "Board Geometry/Outline")
		(27 "Margin" user)
		(31 "F.CrtYd" user "Package Geometry/Place Bound Top")
		(29 "B.CrtYd" user "Package Geometry/Place Bound Bottom")
		(35 "F.Fab" user "Ref Des/Assembly Top")
		(33 "B.Fab" user "Ref Des/Assembly Bottom")
	)
	(footprint ""
		(layer "F.Cu")
		(at 178.1048 -68.453 180)
		(property "Reference" "PG20"
			(at 0 0 180)
			(layer "F.SilkS")
			(hide yes)
			(effects
				(font
					(size 1.27 1.27)
				)
			)
		)
		(property "Value" "GAP-CLOSE-PWR-3-GP"
			(at 0.0254 -6.5786 180)
			(unlocked yes)
			(layer "F.Fab")
			(hide yes)
			(effects
				(font
					(size 1.016 1.016)
					(thickness 0.1524)
				)
			)
		)
		(property "Device Type" "GAP-CLOSE-PWR-3"
			(at 0.0254 -8.255 180)
			(unlocked yes)
			(layer "F.Fab")
			(hide yes)
			(effects
				(font
					(size 1.016 1.016)
					(thickness 0.1524)
				)
			)
		)
		(duplicate_pad_numbers_are_jumpers no)
		(fp_rect
			(start -0.7112 0.4572)
			(end 0.7112 -0.4572)
			(stroke
				(width 0)
				(type default)
			)
			(fill no)
			(layer "F.CrtYd")
		)
		(fp_poly
			(pts
				(xy -0.7112 -0.4572) (xy 0.7112 -0.4572) (xy 0.7112 0.4572) (xy -0.7112 0.4572)
			)
			(stroke
				(width 0)
				(type default)
			)
			(fill no)
			(layer "F.Fab")
		)
		(pad "1" smd rect
			(at -0.3048 0 180)
			(size 0.6604 0.762)
			(layers "F.Cu" "F.Mask" "F.Paste")
			(net "DUT_AVD_PCIE")
		)
		(pad "2" smd rect
			(at 0.3048 0 180)
			(size 0.6604 0.762)
			(layers "F.Cu" "F.Mask" "F.Paste")
			(net "P0V9")
		)
	)
	(footprint ""
		(layer "F.Cu")
		(at 19.177 -147.828 90)
		(property "Reference" "R334"
			(at 0 0 90)
			(layer "F.SilkS")
			(hide yes)
			(effects
				(font
					(size 1.27 1.27)
				)
			)
		)
		(property "Value" "47KR2F-GP"
			(at 0.064008 -3.993896 90)
			(unlocked yes)
			(layer "F.Fab")
			(hide yes)
			(effects
				(font
					(size 1.016 1.016)
					(thickness 0.1524)
				)
			)
		)
		(property "Device Type" "R402H16"
			(at 0.064008 -5.517896 90)
			(unlocked yes)
			(layer "F.Fab")
			(hide yes)
			(effects
				(font
					(size 1.016 1.016)
					(thickness 0.1524)
				)
			)
		)
		(duplicate_pad_numbers_are_jumpers no)
		(fp_line
			(start 0.508 -0.9398)
			(end -0.508 -0.9398)
			(stroke
				(width 0.1524)
				(type default)
			)
			(layer "F.SilkS")
		)
		(fp_line
			(start -0.508 -0.9398)
			(end -0.508 0.9398)
			(stroke
				(width 0.1524)
				(type default)
			)
			(layer "F.SilkS")
		)
		(fp_rect
			(start -0.508 0.9398)
			(end 0.508 -0.9398)
			(stroke
				(width 0)
				(type default)
			)
			(fill no)
			(layer "F.CrtYd")
		)
		(fp_rect
			(start -0.508 0.9398)
			(end 0.508 -0.9398)
			(stroke
				(width 0)
				(type default)
			)
			(fill no)
			(layer "F.Fab")
		)
		(pad "1" smd custom
			(at 0 -0.4445 90)
			(size 0.1397 0.1397)
			(layers "F.Cu" "F.Mask" "F.Paste")
			(net "FM_BMC_RESET_N")
			(options
				(clearance outline)
				(anchor circle)
			)
			(primitives
				(gr_poly
					(pts
						(arc
							(start -0.1778 -0.2794)
							(mid -0.249642 -0.249642)
							(end -0.2794 -0.1778)
						)
						(arc
							(start -0.2794 0.1778)
							(mid -0.249642 0.249642)
							(end -0.1778 0.2794)
						)
						(arc
							(start 0.1778 0.2794)
							(mid 0.249642 0.249642)
							(end 0.2794 0.1778)
						)
						(arc
							(start 0.2794 -0.1778)
							(mid 0.249642 -0.249642)
							(end 0.1778 -0.2794)
						)
					)
					(width 0)
					(fill yes)
				)
			)
		)
		(pad "2" smd custom
			(at 0 0.4445 90)
			(size 0.1397 0.1397)
			(layers "F.Cu" "F.Mask" "F.Paste")
			(net "GND")
			(options
				(clearance outline)
				(anchor circle)
			)
			(primitives
				(gr_poly
					(pts
						(arc
							(start -0.1778 -0.2794)
							(mid -0.249642 -0.249642)
							(end -0.2794 -0.1778)
						)
						(arc
							(start -0.2794 0.1778)
							(mid -0.249642 0.249642)
							(end -0.1778 0.2794)
						)
						(arc
							(start 0.1778 0.2794)
							(mid 0.249642 0.249642)
							(end 0.2794 0.1778)
						)
						(arc
							(start 0.2794 -0.1778)
							(mid 0.249642 -0.249642)
							(end 0.1778 -0.2794)
						)
					)
					(width 0)
					(fill yes)
				)
			)
		)
	)
	(footprint ""
		(layer "F.Cu")
		(at 321.563238 -33.508188 180)
		(property "Reference" "R726"
			(at 0 0 180)
			(layer "F.SilkS")
			(hide yes)
			(effects
				(font
					(size 1.27 1.27)
				)
			)
		)
		(property "Value" "0R2J-2-GP"
			(at 0.064008 -3.993896 180)
			(unlocked yes)
			(layer "F.Fab")
			(hide yes)
			(effects
				(font
					(size 1.016 1.016)
					(thickness 0.1524)
				)
			)
		)
		(property "Device Type" "R402H16"
			(at 0.064008 -5.517896 180)
			(unlocked yes)
			(layer "F.Fab")
			(hide yes)
			(effects
				(font
					(size 1.016 1.016)
					(thickness 0.1524)
				)
			)
		)
		(duplicate_pad_numbers_are_jumpers no)
		(fp_line
			(start 0.508 -0.9398)
			(end -0.508 -0.9398)
			(stroke
				(width 0.1524)
				(type default)
			)
			(layer "F.SilkS")
		)
		(fp_line
			(start -0.508 -0.9398)
			(end -0.508 0.9398)
			(stroke
				(width 0.1524)
				(type default)
			)
			(layer "F.SilkS")
		)
		(fp_rect
			(start -0.508 0.9398)
			(end 0.508 -0.9398)
			(stroke
				(width 0)
				(type default)
			)
			(fill no)
			(layer "F.CrtYd")
		)
		(fp_rect
			(start -0.508 0.9398)
			(end 0.508 -0.9398)
			(stroke
				(width 0)
				(type default)
			)
			(fill no)
			(layer "F.Fab")
		)
		(pad "1" smd custom
			(at 0 -0.4445 180)
			(size 0.1397 0.1397)
			(layers "F.Cu" "F.Mask" "F.Paste")
			(net "8644_USB_DN8")
			(options
				(clearance outline)
				(anchor circle)
			)
			(primitives
				(gr_poly
					(pts
						(arc
							(start -0.1778 -0.2794)
							(mid -0.249642 -0.249642)
							(end -0.2794 -0.1778)
						)
						(arc
							(start -0.2794 0.1778)
							(mid -0.249642 0.249642)
							(end -0.1778 0.2794)
						)
						(arc
							(start 0.1778 0.2794)
							(mid 0.249642 0.249642)
							(end 0.2794 0.1778)
						)
						(arc
							(start 0.2794 -0.1778)
							(mid 0.249642 -0.249642)
							(end 0.1778 -0.2794)
						)
					)
					(width 0)
					(fill yes)
				)
			)
		)
		(pad "2" smd custom
			(at 0 0.4445 180)
			(size 0.1397 0.1397)
			(layers "F.Cu" "F.Mask" "F.Paste")
			(net "P3V3_STBY")
			(options
				(clearance outline)
				(anchor circle)
			)
			(primitives
				(gr_poly
					(pts
						(arc
							(start -0.1778 -0.2794)
							(mid -0.249642 -0.249642)
							(end -0.2794 -0.1778)
						)
						(arc
							(start -0.2794 0.1778)
							(mid -0.249642 0.249642)
							(end -0.1778 0.2794)
						)
						(arc
							(start 0.1778 0.2794)
							(mid 0.249642 0.249642)
							(end 0.2794 0.1778)
						)
						(arc
							(start 0.2794 -0.1778)
							(mid 0.249642 -0.249642)
							(end 0.1778 -0.2794)
						)
					)
					(width 0)
					(fill yes)
				)
			)
		)
	)
	(footprint ""
		(layer "F.Cu")
		(at 203.02474 -6.691122 90)
		(property "Reference" "R3"
			(at 0 0 90)
			(layer "F.SilkS")
			(hide yes)
			(effects
				(font
					(size 1.27 1.27)
				)
			)
		)
		(property "Value" "0R2J-2-GP"
			(at 0.064008 -3.993896 90)
			(unlocked yes)
			(layer "F.Fab")
			(hide yes)
			(effects
				(font
					(size 1.016 1.016)
					(thickness 0.1524)
				)
			)
		)
		(property "Device Type" "R402H16"
			(at 0.064008 -5.517896 90)
			(unlocked yes)
			(layer "F.Fab")
			(hide yes)
			(effects
				(font
					(size 1.016 1.016)
					(thickness 0.1524)
				)
			)
		)
		(duplicate_pad_numbers_are_jumpers no)
		(fp_line
			(start 0.508 -0.9398)
			(end -0.508 -0.9398)
			(stroke
				(width 0.1524)
				(type default)
			)
			(layer "F.SilkS")
		)
		(fp_line
			(start -0.508 -0.9398)
			(end -0.508 0.9398)
			(stroke
				(width 0.1524)
				(type default)
			)
			(layer "F.SilkS")
		)
		(fp_rect
			(start -0.508 0.9398)
			(end 0.508 -0.9398)
			(stroke
				(width 0)
				(type default)
			)
			(fill no)
			(layer "F.CrtYd")
		)
		(fp_rect
			(start -0.508 0.9398)
			(end 0.508 -0.9398)
			(stroke
				(width 0)
				(type default)
			)
			(fill no)
			(layer "F.Fab")
		)
		(pad "1" smd custom
			(at 0 -0.4445 90)
			(size 0.1397 0.1397)
			(layers "F.Cu" "F.Mask" "F.Paste")
			(net "BOOT_RECOVERY#_R")
			(options
				(clearance outline)
				(anchor circle)
			)
			(primitives
				(gr_poly
					(pts
						(arc
							(start -0.1778 -0.2794)
							(mid -0.249642 -0.249642)
							(end -0.2794 -0.1778)
						)
						(arc
							(start -0.2794 0.1778)
							(mid -0.249642 0.249642)
							(end -0.1778 0.2794)
						)
						(arc
							(start 0.1778 0.2794)
							(mid 0.249642 0.249642)
							(end 0.2794 0.1778)
						)
						(arc
							(start 0.2794 -0.1778)
							(mid 0.249642 -0.249642)
							(end 0.1778 -0.2794)
						)
					)
					(width 0)
					(fill yes)
				)
			)
		)
		(pad "2" smd custom
			(at 0 0.4445 90)
			(size 0.1397 0.1397)
			(layers "F.Cu" "F.Mask" "F.Paste")
			(net "BOOT_RECOVERY#")
			(options
				(clearance outline)
				(anchor circle)
			)
			(primitives
				(gr_poly
					(pts
						(arc
							(start -0.1778 -0.2794)
							(mid -0.249642 -0.249642)
							(end -0.2794 -0.1778)
						)
						(arc
							(start -0.2794 0.1778)
							(mid -0.249642 0.249642)
							(end -0.1778 0.2794)
						)
						(arc
							(start 0.1778 0.2794)
							(mid 0.249642 0.249642)
							(end 0.2794 0.1778)
						)
						(arc
							(start 0.2794 -0.1778)
							(mid 0.249642 -0.249642)
							(end 0.1778 -0.2794)
						)
					)
					(width 0)
					(fill yes)
				)
			)
		)
	)
	(footprint ""
		(layer "F.Cu")
		(at 250.549918 -4.721098 90)
		(property "Reference" "R3603"
			(at 0 0 90)
			(layer "F.SilkS")
			(hide yes)
			(effects
				(font
					(size 1.27 1.27)
				)
			)
		)
		(property "Value" "10KR2F-2-GP"
			(at 0.064008 -3.993896 90)
			(unlocked yes)
			(layer "F.Fab")
			(hide yes)
			(effects
				(font
					(size 1.016 1.016)
					(thickness 0.1524)
				)
			)
		)
		(property "Device Type" "R402H16"
			(at 0.064008 -5.517896 90)
			(unlocked yes)
			(layer "F.Fab")
			(hide yes)
			(effects
				(font
					(size 1.016 1.016)
					(thickness 0.1524)
				)
			)
		)
		(duplicate_pad_numbers_are_jumpers no)
		(fp_line
			(start 0.508 -0.9398)
			(end -0.508 -0.9398)
			(stroke
				(width 0.1524)
				(type default)
			)
			(layer "F.SilkS")
		)
		(fp_line
			(start -0.508 -0.9398)
			(end -0.508 0.9398)
			(stroke
				(width 0.1524)
				(type default)
			)
			(layer "F.SilkS")
		)
		(fp_rect
			(start -0.508 0.9398)
			(end 0.508 -0.9398)
			(stroke
				(width 0)
				(type default)
			)
			(fill no)
			(layer "F.CrtYd")
		)
		(fp_rect
			(start -0.508 0.9398)
			(end 0.508 -0.9398)
			(stroke
				(width 0)
				(type default)
			)
			(fill no)
			(layer "F.Fab")
		)
		(pad "1" smd custom
			(at 0 -0.4445 90)
			(size 0.1397 0.1397)
			(layers "F.Cu" "F.Mask" "F.Paste")
			(net "P3V3_STBY")
			(options
				(clearance outline)
				(anchor circle)
			)
			(primitives
				(gr_poly
					(pts
						(arc
							(start -0.1778 -0.2794)
							(mid -0.249642 -0.249642)
							(end -0.2794 -0.1778)
						)
						(arc
							(start -0.2794 0.1778)
							(mid -0.249642 0.249642)
							(end -0.1778 0.2794)
						)
						(arc
							(start 0.1778 0.2794)
							(mid 0.249642 0.249642)
							(end 0.2794 0.1778)
						)
						(arc
							(start 0.2794 -0.1778)
							(mid 0.249642 -0.249642)
							(end 0.1778 -0.2794)
						)
					)
					(width 0)
					(fill yes)
				)
			)
		)
		(pad "2" smd custom
			(at 0 0.4445 90)
			(size 0.1397 0.1397)
			(layers "F.Cu" "F.Mask" "F.Paste")
			(net "MAX6654_ALERT#")
			(options
				(clearance outline)
				(anchor circle)
			)
			(primitives
				(gr_poly
					(pts
						(arc
							(start -0.1778 -0.2794)
							(mid -0.249642 -0.249642)
							(end -0.2794 -0.1778)
						)
						(arc
							(start -0.2794 0.1778)
							(mid -0.249642 0.249642)
							(end -0.1778 0.2794)
						)
						(arc
							(start 0.1778 0.2794)
							(mid 0.249642 0.249642)
							(end 0.2794 0.1778)
						)
						(arc
							(start 0.2794 -0.1778)
							(mid 0.249642 -0.249642)
							(end 0.1778 -0.2794)
						)
					)
					(width 0)
					(fill yes)
				)
			)
		)
	)
	(footprint ""
		(layer "F.Cu")
		(at 327.007982 -212.420454 180)
		(property "Reference" "C63"
			(at 0 0 180)
			(layer "F.SilkS")
			(hide yes)
			(effects
				(font
					(size 1.27 1.27)
				)
			)
		)
		(property "Value" "SCD22U10V2KX-1GP"
			(at 1.1811 -2.7051 180)
			(unlocked yes)
			(layer "F.Fab")
			(hide yes)
			(effects
				(font
					(size 1.016 1.016)
					(thickness 0.1524)
				)
			)
		)
		(property "Device Type" "C402H22"
			(at 1.1811 -4.2291 180)
			(unlocked yes)
			(layer "F.Fab")
			(hide yes)
			(effects
				(font
					(size 1.016 1.016)
					(thickness 0.1524)
				)
			)
		)
		(duplicate_pad_numbers_are_jumpers no)
		(fp_rect
			(start -0.4318 0.9525)
			(end 0.4318 -0.9525)
			(stroke
				(width 0)
				(type default)
			)
			(fill no)
			(layer "F.CrtYd")
		)
		(fp_rect
			(start -0.4318 0.9525)
			(end 0.4318 -0.9525)
			(stroke
				(width 0)
				(type default)
			)
			(fill no)
			(layer "F.Fab")
		)
		(pad "1" smd custom
			(at 0 -0.4445 180)
			(size 0.1524 0.1524)
			(layers "F.Cu" "F.Mask" "F.Paste")
			(net "PCIE_TX_CAP_N20")
			(options
				(clearance outline)
				(anchor circle)
			)
			(primitives
				(gr_poly
					(pts
						(arc
							(start 0.3048 -0.2032)
							(mid 0.275042 -0.275042)
							(end 0.2032 -0.3048)
						)
						(arc
							(start -0.2032 -0.3048)
							(mid -0.275042 -0.275042)
							(end -0.3048 -0.2032)
						)
						(arc
							(start -0.3048 0.2032)
							(mid -0.275042 0.275042)
							(end -0.2032 0.3048)
						)
						(arc
							(start 0.2032 0.3048)
							(mid 0.275042 0.275042)
							(end 0.3048 0.2032)
						)
					)
					(width 0)
					(fill yes)
				)
			)
		)
		(pad "2" smd custom
			(at 0 0.4445 180)
			(size 0.1524 0.1524)
			(layers "F.Cu" "F.Mask" "F.Paste")
			(net "PCIE_TX_N20")
			(options
				(clearance outline)
				(anchor circle)
			)
			(primitives
				(gr_poly
					(pts
						(arc
							(start 0.3048 -0.2032)
							(mid 0.275042 -0.275042)
							(end 0.2032 -0.3048)
						)
						(arc
							(start -0.2032 -0.3048)
							(mid -0.275042 -0.275042)
							(end -0.3048 -0.2032)
						)
						(arc
							(start -0.3048 0.2032)
							(mid -0.275042 0.275042)
							(end -0.2032 0.3048)
						)
						(arc
							(start 0.2032 0.3048)
							(mid 0.275042 0.275042)
							(end 0.3048 0.2032)
						)
					)
					(width 0)
					(fill yes)
				)
			)
		)
	)
	(footprint ""
		(layer "F.Cu")
		(at 152.111202 -67.083432 90)
		(property "Reference" "PC192"
			(at 0 0 90)
			(layer "F.SilkS")
			(hide yes)
			(effects
				(font
					(size 1.27 1.27)
				)
			)
		)
		(property "Value" "SC10U25V5KX-GP"
			(at -0.0762 -6.1214 90)
			(unlocked yes)
			(layer "F.Fab")
			(hide yes)
			(effects
				(font
					(size 1.016 1.016)
					(thickness 0.1524)
				)
			)
		)
		(property "Device Type" "C805H56"
			(at -0.0762 -8.1534 90)
			(unlocked yes)
			(layer "F.Fab")
			(hide yes)
			(effects
				(font
					(size 1.016 1.016)
					(thickness 0.1524)
				)
			)
		)
		(duplicate_pad_numbers_are_jumpers no)
		(fp_line
			(start 0.635 0)
			(end -0.635 0)
			(stroke
				(width 0.508)
				(type default)
			)
			(layer "F.SilkS")
		)
		(fp_rect
			(start -0.9652 1.778)
			(end 0.9652 -1.778)
			(stroke
				(width 0)
				(type default)
			)
			(fill no)
			(layer "F.CrtYd")
		)
		(fp_poly
			(pts
				(xy -0.9652 -1.778) (xy 0.9652 -1.778) (xy 0.9652 1.778) (xy -0.9652 1.778)
			)
			(stroke
				(width 0)
				(type default)
			)
			(fill no)
			(layer "F.Fab")
		)
		(pad "1" smd rect
			(at 0 -0.9652 90)
			(size 1.397 1.143)
			(layers "F.Cu" "F.Mask" "F.Paste")
			(net "P0V9_VIN")
		)
		(pad "2" smd rect
			(at 0 0.9652 90)
			(size 1.397 1.143)
			(layers "F.Cu" "F.Mask" "F.Paste")
			(net "GND")
		)
	)
	(footprint ""
		(layer "F.Cu")
		(at 32.814006 -83.803744 180)
		(property "Reference" "R734"
			(at 0 0 180)
			(layer "F.SilkS")
			(hide yes)
			(effects
				(font
					(size 1.27 1.27)
				)
			)
		)
		(property "Value" "47R6F-GP"
			(at -0.0508 -4.8514 180)
			(unlocked yes)
			(layer "F.Fab")
			(hide yes)
			(effects
				(font
					(size 1.016 1.016)
					(thickness 0.1524)
				)
			)
		)
		(property "Device Type" "R1206H26"
			(at 0 -6.3754 180)
			(unlocked yes)
			(layer "F.Fab")
			(hide yes)
			(effects
				(font
					(size 1.016 1.016)
					(thickness 0.1524)
				)
			)
		)
		(duplicate_pad_numbers_are_jumpers no)
		(fp_line
			(start 1.016 2.2352)
			(end -1.016 2.2352)
			(stroke
				(width 0.1524)
				(type default)
			)
			(layer "F.SilkS")
		)
		(fp_line
			(start 1.016 -2.2352)
			(end 1.016 2.2352)
			(stroke
				(width 0.1524)
				(type default)
			)
			(layer "F.SilkS")
		)
		(fp_line
			(start -1.016 2.2352)
			(end -1.016 -2.2352)
			(stroke
				(width 0.1524)
				(type default)
			)
			(layer "F.SilkS")
		)
		(fp_line
			(start -1.016 -2.2352)
			(end 1.016 -2.2352)
			(stroke
				(width 0.1524)
				(type default)
			)
			(layer "F.SilkS")
		)
		(fp_rect
			(start -1.0922 2.3114)
			(end 1.0922 -2.3114)
			(stroke
				(width 0)
				(type default)
			)
			(fill no)
			(layer "F.CrtYd")
		)
		(fp_poly
			(pts
				(xy -1.0922 -2.3114) (xy 1.0922 -2.3114) (xy 1.0922 2.3114) (xy -1.0922 2.3114)
			)
			(stroke
				(width 0)
				(type default)
			)
			(fill no)
			(layer "F.Fab")
		)
		(pad "1" smd rect
			(at 0 -1.397 180)
			(size 1.651 1.27)
			(layers "F.Cu" "F.Mask" "F.Paste")
			(net "P5V_STBY")
		)
		(pad "2" smd rect
			(at 0 1.397 180)
			(size 1.651 1.27)
			(layers "F.Cu" "F.Mask" "F.Paste")
			(net "Q46_D")
		)
	)
)
